(kicad_pcb
	(version 20260206)
	(generator "pcbnew")
	(generator_version "10.0")
	(general
		(thickness 1.6)
		(legacy_teardrops no)
	)
	(paper "A4")
	(title_block
		(title "baseboard — 13948-1b.1110WZS1818.brd")
		(comment 1 "Honey Badger (Wiwynn) / footprints 1383-1390 of 2523")
	)
	(layers
		(0 "F.Cu" signal "TOP")
		(4 "In1.Cu" signal "L2GND")
		(6 "In2.Cu" signal "L3")
		(8 "In3.Cu" signal "L4VCC")
		(10 "In4.Cu" signal "L5VCC")
		(12 "In5.Cu" signal "L6")
		(14 "In6.Cu" signal "L7GND")
		(2 "B.Cu" signal "BOTTOM")
		(9 "F.Adhes" user "F.Adhesive")
		(11 "B.Adhes" user "B.Adhesive")
		(13 "F.Paste" user "Package Geometry/Pastemask Top")
		(15 "B.Paste" user "Package Geometry/Pastemask Bottom")
		(5 "F.SilkS" user "Ref Des/Silkscreen Top")
		(7 "B.SilkS" user "Ref Des/Silkscreen Bottom")
		(1 "F.Mask" user "Board Geometry/Soldermask Top")
		(3 "B.Mask" user "Board Geometry/Soldermask Bottom")
		(17 "Dwgs.User" user "User.Drawings")
		(19 "Cmts.User" user "User.Comments")
		(21 "Eco1.User" user "User.Eco1")
		(23 "Eco2.User" user "User.Eco2")
		(25 "Edge.Cuts" user "Board Geometry/Outline")
		(27 "Margin" user)
		(31 "F.CrtYd" user "Package Geometry/Place Bound Top")
		(29 "B.CrtYd" user "Package Geometry/Place Bound Bottom")
		(35 "F.Fab" user "Ref Des/Assembly Top")
		(33 "B.Fab" user "Ref Des/Assembly Bottom")
	)
	(footprint ""
		(layer "F.Cu")
		(at 146.939 -15.748 -90)
		(property "Reference" "C325"
			(at 0 0 270)
			(layer "F.SilkS")
			(hide yes)
			(effects
				(font
					(size 1.27 1.27)
				)
			)
		)
		(property "Value" "SCD1U16V2KX-3GP"
			(at 1.1811 -2.7051 270)
			(unlocked yes)
			(layer "F.Fab")
			(hide yes)
			(effects
				(font
					(size 1.016 1.016)
					(thickness 0.1524)
				)
			)
		)
		(property "Device Type" "C402H22"
			(at 1.1811 -4.2291 270)
			(unlocked yes)
			(layer "F.Fab")
			(hide yes)
			(effects
				(font
					(size 1.016 1.016)
					(thickness 0.1524)
				)
			)
		)
		(duplicate_pad_numbers_are_jumpers no)
		(fp_rect
			(start -0.4318 0.9525)
			(end 0.4318 -0.9525)
			(stroke
				(width 0)
				(type default)
			)
			(fill no)
			(layer "F.CrtYd")
		)
		(fp_rect
			(start -0.4318 0.9525)
			(end 0.4318 -0.9525)
			(stroke
				(width 0)
				(type default)
			)
			(fill no)
			(layer "F.Fab")
		)
		(pad "1" smd custom
			(at 0 -0.4445 270)
			(size 0.1524 0.1524)
			(layers "F.Cu" "F.Mask" "F.Paste")
			(net "PHY_AVDD")
			(options
				(clearance outline)
				(anchor circle)
			)
			(primitives
				(gr_poly
					(pts
						(arc
							(start 0.3048 -0.2032)
							(mid 0.275042 -0.275042)
							(end 0.2032 -0.3048)
						)
						(arc
							(start -0.2032 -0.3048)
							(mid -0.275042 -0.275042)
							(end -0.3048 -0.2032)
						)
						(arc
							(start -0.3048 0.2032)
							(mid -0.275042 0.275042)
							(end -0.2032 0.3048)
						)
						(arc
							(start 0.2032 0.3048)
							(mid 0.275042 0.275042)
							(end 0.3048 0.2032)
						)
					)
					(width 0)
					(fill yes)
				)
			)
		)
		(pad "2" smd custom
			(at 0 0.4445 270)
			(size 0.1524 0.1524)
			(layers "F.Cu" "F.Mask" "F.Paste")
			(net "GND")
			(options
				(clearance outline)
				(anchor circle)
			)
			(primitives
				(gr_poly
					(pts
						(arc
							(start 0.3048 -0.2032)
							(mid 0.275042 -0.275042)
							(end 0.2032 -0.3048)
						)
						(arc
							(start -0.2032 -0.3048)
							(mid -0.275042 -0.275042)
							(end -0.3048 -0.2032)
						)
						(arc
							(start -0.3048 0.2032)
							(mid -0.275042 0.275042)
							(end -0.2032 0.3048)
						)
						(arc
							(start 0.2032 0.3048)
							(mid 0.275042 0.275042)
							(end 0.3048 0.2032)
						)
					)
					(width 0)
					(fill yes)
				)
			)
		)
	)
	(footprint ""
		(layer "F.Cu")
		(at 107.70997 -114.3 180)
		(property "Reference" "SC1083"
			(at 0 0 180)
			(layer "F.SilkS")
			(hide yes)
			(effects
				(font
					(size 1.27 1.27)
				)
			)
		)
		(property "Value" "SCD01U10V1KX-GP"
			(at -2.8321 -1.7399 180)
			(unlocked yes)
			(layer "F.Fab")
			(hide yes)
			(effects
				(font
					(size 1.016 1.016)
					(thickness 0.1524)
				)
			)
		)
		(property "Device Type" "C0201H13"
			(at -2.8321 -3.2639 180)
			(unlocked yes)
			(layer "F.Fab")
			(hide yes)
			(effects
				(font
					(size 1.016 1.016)
					(thickness 0.1524)
				)
			)
		)
		(duplicate_pad_numbers_are_jumpers no)
		(fp_rect
			(start -0.2794 0.6477)
			(end 0.2794 -0.6477)
			(stroke
				(width 0)
				(type default)
			)
			(fill no)
			(layer "F.CrtYd")
		)
		(fp_rect
			(start -0.2794 0.6477)
			(end 0.2794 -0.6477)
			(stroke
				(width 0)
				(type default)
			)
			(fill no)
			(layer "F.Fab")
		)
		(pad "1" smd custom
			(at 0 -0.2794 180)
			(size 0.0762 0.0762)
			(layers "F.Cu" "F.Mask" "F.Paste")
			(net "SAS_HDD_TX8_P")
			(options
				(clearance outline)
				(anchor circle)
			)
			(primitives
				(gr_poly
					(pts
						(arc
							(start 0.1524 -0.127)
							(mid 0.137521 -0.162921)
							(end 0.1016 -0.1778)
						)
						(arc
							(start -0.1016 -0.1778)
							(mid -0.137521 -0.162921)
							(end -0.1524 -0.127)
						)
						(arc
							(start -0.1524 0.127)
							(mid -0.137521 0.162921)
							(end -0.1016 0.1778)
						)
						(arc
							(start 0.1016 0.1778)
							(mid 0.137521 0.162921)
							(end 0.1524 0.127)
						)
					)
					(width 0)
					(fill yes)
				)
			)
		)
		(pad "2" smd custom
			(at 0 0.2794 180)
			(size 0.0762 0.0762)
			(layers "F.Cu" "F.Mask" "F.Paste")
			(net "SAS_EXP_GF_TX_DP12")
			(options
				(clearance outline)
				(anchor circle)
			)
			(primitives
				(gr_poly
					(pts
						(arc
							(start 0.1524 -0.127)
							(mid 0.137521 -0.162921)
							(end 0.1016 -0.1778)
						)
						(arc
							(start -0.1016 -0.1778)
							(mid -0.137521 -0.162921)
							(end -0.1524 -0.127)
						)
						(arc
							(start -0.1524 0.127)
							(mid -0.137521 0.162921)
							(end -0.1016 0.1778)
						)
						(arc
							(start 0.1016 0.1778)
							(mid 0.137521 0.162921)
							(end 0.1524 0.127)
						)
					)
					(width 0)
					(fill yes)
				)
			)
		)
	)
	(footprint ""
		(layer "F.Cu")
		(at 215.773 -181.737 90)
		(property "Reference" "R494"
			(at 0 0 90)
			(layer "F.SilkS")
			(hide yes)
			(effects
				(font
					(size 1.27 1.27)
				)
			)
		)
		(property "Value" "2MR2F-GP"
			(at 0.064008 -3.993896 90)
			(unlocked yes)
			(layer "F.Fab")
			(hide yes)
			(effects
				(font
					(size 1.016 1.016)
					(thickness 0.1524)
				)
			)
		)
		(property "Device Type" "R402H16"
			(at 0.064008 -5.517896 90)
			(unlocked yes)
			(layer "F.Fab")
			(hide yes)
			(effects
				(font
					(size 1.016 1.016)
					(thickness 0.1524)
				)
			)
		)
		(duplicate_pad_numbers_are_jumpers no)
		(fp_line
			(start 0.508 -0.9398)
			(end -0.508 -0.9398)
			(stroke
				(width 0.1524)
				(type default)
			)
			(layer "F.SilkS")
		)
		(fp_line
			(start -0.508 -0.9398)
			(end -0.508 0.9398)
			(stroke
				(width 0.1524)
				(type default)
			)
			(layer "F.SilkS")
		)
		(fp_rect
			(start -0.508 0.9398)
			(end 0.508 -0.9398)
			(stroke
				(width 0)
				(type default)
			)
			(fill no)
			(layer "F.CrtYd")
		)
		(fp_rect
			(start -0.508 0.9398)
			(end 0.508 -0.9398)
			(stroke
				(width 0)
				(type default)
			)
			(fill no)
			(layer "F.Fab")
		)
		(pad "1" smd custom
			(at 0 -0.4445 90)
			(size 0.1397 0.1397)
			(layers "F.Cu" "F.Mask" "F.Paste")
			(net "EXP_HB")
			(options
				(clearance outline)
				(anchor circle)
			)
			(primitives
				(gr_poly
					(pts
						(arc
							(start -0.1778 -0.2794)
							(mid -0.249642 -0.249642)
							(end -0.2794 -0.1778)
						)
						(arc
							(start -0.2794 0.1778)
							(mid -0.249642 0.249642)
							(end -0.1778 0.2794)
						)
						(arc
							(start 0.1778 0.2794)
							(mid 0.249642 0.249642)
							(end 0.2794 0.1778)
						)
						(arc
							(start 0.2794 -0.1778)
							(mid 0.249642 -0.249642)
							(end 0.1778 -0.2794)
						)
					)
					(width 0)
					(fill yes)
				)
			)
		)
		(pad "2" smd custom
			(at 0 0.4445 90)
			(size 0.1397 0.1397)
			(layers "F.Cu" "F.Mask" "F.Paste")
			(net "HB_A_IN_EXP")
			(options
				(clearance outline)
				(anchor circle)
			)
			(primitives
				(gr_poly
					(pts
						(arc
							(start -0.1778 -0.2794)
							(mid -0.249642 -0.249642)
							(end -0.2794 -0.1778)
						)
						(arc
							(start -0.2794 0.1778)
							(mid -0.249642 0.249642)
							(end -0.1778 0.2794)
						)
						(arc
							(start 0.1778 0.2794)
							(mid 0.249642 0.249642)
							(end 0.2794 0.1778)
						)
						(arc
							(start 0.2794 -0.1778)
							(mid 0.249642 -0.249642)
							(end 0.1778 -0.2794)
						)
					)
					(width 0)
					(fill yes)
				)
			)
		)
	)
	(footprint ""
		(layer "F.Cu")
		(at 274.438872 -53.158136 180)
		(property "Reference" "PR116"
			(at 0 0 180)
			(layer "F.SilkS")
			(hide yes)
			(effects
				(font
					(size 1.27 1.27)
				)
			)
		)
		(property "Value" "20KR2F-L-GP"
			(at 0.064008 -3.993896 180)
			(unlocked yes)
			(layer "F.Fab")
			(hide yes)
			(effects
				(font
					(size 1.016 1.016)
					(thickness 0.1524)
				)
			)
		)
		(property "Device Type" "R402H16"
			(at 0.064008 -5.517896 180)
			(unlocked yes)
			(layer "F.Fab")
			(hide yes)
			(effects
				(font
					(size 1.016 1.016)
					(thickness 0.1524)
				)
			)
		)
		(duplicate_pad_numbers_are_jumpers no)
		(fp_line
			(start 0.508 -0.9398)
			(end -0.508 -0.9398)
			(stroke
				(width 0.1524)
				(type default)
			)
			(layer "F.SilkS")
		)
		(fp_line
			(start -0.508 -0.9398)
			(end -0.508 0.9398)
			(stroke
				(width 0.1524)
				(type default)
			)
			(layer "F.SilkS")
		)
		(fp_rect
			(start -0.508 0.9398)
			(end 0.508 -0.9398)
			(stroke
				(width 0)
				(type default)
			)
			(fill no)
			(layer "F.CrtYd")
		)
		(fp_rect
			(start -0.508 0.9398)
			(end 0.508 -0.9398)
			(stroke
				(width 0)
				(type default)
			)
			(fill no)
			(layer "F.Fab")
		)
		(pad "1" smd custom
			(at 0 -0.4445 180)
			(size 0.1397 0.1397)
			(layers "F.Cu" "F.Mask" "F.Paste")
			(net "P12V")
			(options
				(clearance outline)
				(anchor circle)
			)
			(primitives
				(gr_poly
					(pts
						(arc
							(start -0.1778 -0.2794)
							(mid -0.249642 -0.249642)
							(end -0.2794 -0.1778)
						)
						(arc
							(start -0.2794 0.1778)
							(mid -0.249642 0.249642)
							(end -0.1778 0.2794)
						)
						(arc
							(start 0.1778 0.2794)
							(mid 0.249642 0.249642)
							(end 0.2794 0.1778)
						)
						(arc
							(start 0.2794 -0.1778)
							(mid 0.249642 -0.249642)
							(end 0.1778 -0.2794)
						)
					)
					(width 0)
					(fill yes)
				)
			)
		)
		(pad "2" smd custom
			(at 0 0.4445 180)
			(size 0.1397 0.1397)
			(layers "F.Cu" "F.Mask" "F.Paste")
			(net "P3V3_EN_LV")
			(options
				(clearance outline)
				(anchor circle)
			)
			(primitives
				(gr_poly
					(pts
						(arc
							(start -0.1778 -0.2794)
							(mid -0.249642 -0.249642)
							(end -0.2794 -0.1778)
						)
						(arc
							(start -0.2794 0.1778)
							(mid -0.249642 0.249642)
							(end -0.1778 0.2794)
						)
						(arc
							(start 0.1778 0.2794)
							(mid 0.249642 0.249642)
							(end 0.2794 0.1778)
						)
						(arc
							(start 0.2794 -0.1778)
							(mid 0.249642 -0.249642)
							(end 0.1778 -0.2794)
						)
					)
					(width 0)
					(fill yes)
				)
			)
		)
	)
	(footprint ""
		(layer "F.Cu")
		(at 147.290028 -69.469)
		(property "Reference" "C270"
			(at 0 0 0)
			(layer "F.SilkS")
			(hide yes)
			(effects
				(font
					(size 1.27 1.27)
				)
			)
		)
		(property "Value" "SC22U25V5MX-GP"
			(at -0.0762 -6.1214 0)
			(unlocked yes)
			(layer "F.Fab")
			(hide yes)
			(effects
				(font
					(size 1.016 1.016)
					(thickness 0.1524)
				)
			)
		)
		(property "Device Type" "C805H58"
			(at -0.0762 -8.1534 0)
			(unlocked yes)
			(layer "F.Fab")
			(hide yes)
			(effects
				(font
					(size 1.016 1.016)
					(thickness 0.1524)
				)
			)
		)
		(duplicate_pad_numbers_are_jumpers no)
		(fp_line
			(start 0.635 0)
			(end -0.635 0)
			(stroke
				(width 0.508)
				(type default)
			)
			(layer "F.SilkS")
		)
		(fp_rect
			(start -0.9652 1.778)
			(end 0.9652 -1.778)
			(stroke
				(width 0)
				(type default)
			)
			(fill no)
			(layer "F.CrtYd")
		)
		(fp_poly
			(pts
				(xy -0.9652 -1.778) (xy 0.9652 -1.778) (xy 0.9652 1.778) (xy -0.9652 1.778)
			)
			(stroke
				(width 0)
				(type default)
			)
			(fill no)
			(layer "F.Fab")
		)
		(pad "1" smd rect
			(at 0 -0.9652)
			(size 1.397 1.143)
			(layers "F.Cu" "F.Mask" "F.Paste")
			(net "P12V_MSB")
		)
		(pad "2" smd rect
			(at 0 0.9652)
			(size 1.397 1.143)
			(layers "F.Cu" "F.Mask" "F.Paste")
			(net "GND")
		)
	)
	(footprint ""
		(layer "F.Cu")
		(at 315.468 -150.622 -90)
		(property "Reference" "R5200"
			(at 0 0 270)
			(layer "F.SilkS")
			(hide yes)
			(effects
				(font
					(size 1.27 1.27)
				)
			)
		)
		(property "Value" "0R2J-2-GP"
			(at 0.064008 -3.993896 270)
			(unlocked yes)
			(layer "F.Fab")
			(hide yes)
			(effects
				(font
					(size 1.016 1.016)
					(thickness 0.1524)
				)
			)
		)
		(property "Device Type" "R402H16"
			(at 0.064008 -5.517896 270)
			(unlocked yes)
			(layer "F.Fab")
			(hide yes)
			(effects
				(font
					(size 1.016 1.016)
					(thickness 0.1524)
				)
			)
		)
		(duplicate_pad_numbers_are_jumpers no)
		(fp_line
			(start -0.508 -0.9398)
			(end -0.508 0.9398)
			(stroke
				(width 0.1524)
				(type default)
			)
			(layer "F.SilkS")
		)
		(fp_line
			(start 0.508 -0.9398)
			(end -0.508 -0.9398)
			(stroke
				(width 0.1524)
				(type default)
			)
			(layer "F.SilkS")
		)
		(fp_rect
			(start -0.508 0.9398)
			(end 0.508 -0.9398)
			(stroke
				(width 0)
				(type default)
			)
			(fill no)
			(layer "F.CrtYd")
		)
		(fp_rect
			(start -0.508 0.9398)
			(end 0.508 -0.9398)
			(stroke
				(width 0)
				(type default)
			)
			(fill no)
			(layer "F.Fab")
		)
		(pad "1" smd custom
			(at 0 -0.4445 270)
			(size 0.1397 0.1397)
			(layers "F.Cu" "F.Mask" "F.Paste")
			(net "RTC_I2C_SCL")
			(options
				(clearance outline)
				(anchor circle)
			)
			(primitives
				(gr_poly
					(pts
						(arc
							(start -0.1778 -0.2794)
							(mid -0.249642 -0.249642)
							(end -0.2794 -0.1778)
						)
						(arc
							(start -0.2794 0.1778)
							(mid -0.249642 0.249642)
							(end -0.1778 0.2794)
						)
						(arc
							(start 0.1778 0.2794)
							(mid 0.249642 0.249642)
							(end 0.2794 0.1778)
						)
						(arc
							(start 0.2794 -0.1778)
							(mid 0.249642 -0.249642)
							(end 0.1778 -0.2794)
						)
					)
					(width 0)
					(fill yes)
				)
			)
		)
		(pad "2" smd custom
			(at 0 0.4445 270)
			(size 0.1397 0.1397)
			(layers "F.Cu" "F.Mask" "F.Paste")
			(net "BMC_I2C_A_SCL")
			(options
				(clearance outline)
				(anchor circle)
			)
			(primitives
				(gr_poly
					(pts
						(arc
							(start -0.1778 -0.2794)
							(mid -0.249642 -0.249642)
							(end -0.2794 -0.1778)
						)
						(arc
							(start -0.2794 0.1778)
							(mid -0.249642 0.249642)
							(end -0.1778 0.2794)
						)
						(arc
							(start 0.1778 0.2794)
							(mid 0.249642 0.249642)
							(end 0.2794 0.1778)
						)
						(arc
							(start 0.2794 -0.1778)
							(mid 0.249642 -0.249642)
							(end 0.1778 -0.2794)
						)
					)
					(width 0)
					(fill yes)
				)
			)
		)
	)
	(footprint ""
		(layer "F.Cu")
		(at 83.18119 -56.355488 90)
		(property "Reference" "SC921"
			(at 0 0 90)
			(layer "F.SilkS")
			(hide yes)
			(effects
				(font
					(size 1.27 1.27)
				)
			)
		)
		(property "Value" "SC1U6D3V1MX-GP"
			(at 1.9177 2.0193 90)
			(unlocked yes)
			(layer "F.Fab")
			(hide yes)
			(effects
				(font
					(size 1.016 1.016)
					(thickness 0.1524)
				)
			)
		)
		(property "Device Type" "C0201H14"
			(at 1.9177 0.4953 90)
			(unlocked yes)
			(layer "F.Fab")
			(hide yes)
			(effects
				(font
					(size 1.016 1.016)
					(thickness 0.1524)
				)
			)
		)
		(duplicate_pad_numbers_are_jumpers no)
		(fp_rect
			(start -0.1524 0.3048)
			(end 0.1524 -0.3048)
			(stroke
				(width 0)
				(type default)
			)
			(fill no)
			(layer "F.CrtYd")
		)
		(fp_poly
			(pts
				(xy -0.2794 0.6477) (xy -0.2794 -0.6477) (xy 0.2794 -0.6477) (xy 0.2794 -0.1905) (xy 0.1524 -0.1905)
				(xy 0.1524 -0.3048) (xy -0.1524 -0.3048) (xy -0.1524 0.3048) (xy 0.1524 0.3048) (xy 0.1524 -0.1778)
				(xy 0.2794 -0.1778) (xy 0.2794 0.6477)
			)
			(stroke
				(width 0)
				(type default)
			)
			(fill no)
			(layer "F.CrtYd")
		)
		(fp_rect
			(start -0.2794 0.6477)
			(end 0.2794 -0.6477)
			(stroke
				(width 0)
				(type default)
			)
			(fill no)
			(layer "F.Fab")
		)
		(pad "1" smd custom
			(at 0 -0.2794 90)
			(size 0.0762 0.0762)
			(layers "F.Cu" "F.Mask" "F.Paste")
			(net "SYS_PLL_VDD")
			(options
				(clearance outline)
				(anchor circle)
			)
			(primitives
				(gr_poly
					(pts
						(arc
							(start 0.1524 -0.127)
							(mid 0.137521 -0.162921)
							(end 0.1016 -0.1778)
						)
						(arc
							(start -0.1016 -0.1778)
							(mid -0.137521 -0.162921)
							(end -0.1524 -0.127)
						)
						(arc
							(start -0.1524 0.127)
							(mid -0.137521 0.162921)
							(end -0.1016 0.1778)
						)
						(arc
							(start 0.1016 0.1778)
							(mid 0.137521 0.162921)
							(end 0.1524 0.127)
						)
					)
					(width 0)
					(fill yes)
				)
			)
		)
		(pad "2" smd custom
			(at 0 0.2794 90)
			(size 0.0762 0.0762)
			(layers "F.Cu" "F.Mask" "F.Paste")
			(net "GND")
			(options
				(clearance outline)
				(anchor circle)
			)
			(primitives
				(gr_poly
					(pts
						(arc
							(start 0.1524 -0.127)
							(mid 0.137521 -0.162921)
							(end 0.1016 -0.1778)
						)
						(arc
							(start -0.1016 -0.1778)
							(mid -0.137521 -0.162921)
							(end -0.1524 -0.127)
						)
						(arc
							(start -0.1524 0.127)
							(mid -0.137521 0.162921)
							(end -0.1016 0.1778)
						)
						(arc
							(start 0.1016 0.1778)
							(mid 0.137521 0.162921)
							(end 0.1524 0.127)
						)
					)
					(width 0)
					(fill yes)
				)
			)
		)
	)
	(footprint ""
		(layer "F.Cu")
		(at 25.282144 -193.351404 180)
		(property "Reference" "R652"
			(at 0 0 180)
			(layer "F.SilkS")
			(hide yes)
			(effects
				(font
					(size 1.27 1.27)
				)
			)
		)
		(property "Value" "4K7R2F-GP"
			(at 0.064008 -3.993896 180)
			(unlocked yes)
			(layer "F.Fab")
			(hide yes)
			(effects
				(font
					(size 1.016 1.016)
					(thickness 0.1524)
				)
			)
		)
		(property "Device Type" "R402H16"
			(at 0.064008 -5.517896 180)
			(unlocked yes)
			(layer "F.Fab")
			(hide yes)
			(effects
				(font
					(size 1.016 1.016)
					(thickness 0.1524)
				)
			)
		)
		(duplicate_pad_numbers_are_jumpers no)
		(fp_line
			(start 0.508 -0.9398)
			(end -0.508 -0.9398)
			(stroke
				(width 0.1524)
				(type default)
			)
			(layer "F.SilkS")
		)
		(fp_line
			(start -0.508 -0.9398)
			(end -0.508 0.9398)
			(stroke
				(width 0.1524)
				(type default)
			)
			(layer "F.SilkS")
		)
		(fp_rect
			(start -0.508 0.9398)
			(end 0.508 -0.9398)
			(stroke
				(width 0)
				(type default)
			)
			(fill no)
			(layer "F.CrtYd")
		)
		(fp_rect
			(start -0.508 0.9398)
			(end 0.508 -0.9398)
			(stroke
				(width 0)
				(type default)
			)
			(fill no)
			(layer "F.Fab")
		)
		(pad "1" smd custom
			(at 0 -0.4445 180)
			(size 0.1397 0.1397)
			(layers "F.Cu" "F.Mask" "F.Paste")
			(net "IO_EXP_HDD_PRE_A0")
			(options
				(clearance outline)
				(anchor circle)
			)
			(primitives
				(gr_poly
					(pts
						(arc
							(start -0.1778 -0.2794)
							(mid -0.249642 -0.249642)
							(end -0.2794 -0.1778)
						)
						(arc
							(start -0.2794 0.1778)
							(mid -0.249642 0.249642)
							(end -0.1778 0.2794)
						)
						(arc
							(start 0.1778 0.2794)
							(mid 0.249642 0.249642)
							(end 0.2794 0.1778)
						)
						(arc
							(start 0.2794 -0.1778)
							(mid 0.249642 -0.249642)
							(end 0.1778 -0.2794)
						)
					)
					(width 0)
					(fill yes)
				)
			)
		)
		(pad "2" smd custom
			(at 0 0.4445 180)
			(size 0.1397 0.1397)
			(layers "F.Cu" "F.Mask" "F.Paste")
			(net "GND")
			(options
				(clearance outline)
				(anchor circle)
			)
			(primitives
				(gr_poly
					(pts
						(arc
							(start -0.1778 -0.2794)
							(mid -0.249642 -0.249642)
							(end -0.2794 -0.1778)
						)
						(arc
							(start -0.2794 0.1778)
							(mid -0.249642 0.249642)
							(end -0.1778 0.2794)
						)
						(arc
							(start 0.1778 0.2794)
							(mid 0.249642 0.249642)
							(end 0.2794 0.1778)
						)
						(arc
							(start 0.2794 -0.1778)
							(mid 0.249642 -0.249642)
							(end 0.1778 -0.2794)
						)
					)
					(width 0)
					(fill yes)
				)
			)
		)
	)
)
